(kicad_pcb
	(version 20260206)
	(generator "pcbnew")
	(generator_version "10.0")
	(general
		(thickness 1.6)
		(legacy_teardrops no)
	)
	(paper "A4")
	(title_block
		(title "04192023_DAF0TMB3IC0_F0TG_MB_C_brd_V02_OCP.brd")
		(comment 1 "Grand Teton / footprints 3537-3542 of 8354")
	)
	(layers
		(0 "F.Cu" signal "TOP")
		(4 "In1.Cu" signal "GND")
		(6 "In2.Cu" signal "IN1")
		(8 "In3.Cu" signal "GND1")
		(10 "In4.Cu" signal "IN2")
		(12 "In5.Cu" signal "GND2")
		(14 "In6.Cu" signal "IN3")
		(16 "In7.Cu" signal "GND3")
		(18 "In8.Cu" signal "VCC")
		(20 "In9.Cu" signal "VCC1")
		(22 "In10.Cu" signal "GND4")
		(24 "In11.Cu" signal "IN4")
		(26 "In12.Cu" signal "GND5")
		(28 "In13.Cu" signal "IN5")
		(30 "In14.Cu" signal "GND6")
		(32 "In15.Cu" signal "IN6")
		(34 "In16.Cu" signal "GND7")
		(2 "B.Cu" signal "BOTTOM")
		(9 "F.Adhes" user "F.Adhesive")
		(11 "B.Adhes" user "B.Adhesive")
		(13 "F.Paste" user "Package Geometry/Pastemask Top")
		(15 "B.Paste" user "Package Geometry/Pastemask Bottom")
		(5 "F.SilkS" user "Ref Des/Silkscreen Top")
		(7 "B.SilkS" user "Ref Des/Silkscreen Bottom")
		(1 "F.Mask" user "Board Geometry/Soldermask Top")
		(3 "B.Mask" user "Board Geometry/Soldermask Bottom")
		(17 "Dwgs.User" user "User.Drawings")
		(19 "Cmts.User" user "User.Comments")
		(21 "Eco1.User" user "User.Eco1")
		(23 "Eco2.User" user "User.Eco2")
		(25 "Edge.Cuts" user "Board Geometry/Outline")
		(27 "Margin" user)
		(31 "F.CrtYd" user "Package Geometry/Place Bound Top")
		(29 "B.CrtYd" user "Package Geometry/Place Bound Bottom")
		(35 "F.Fab" user "Ref Des/Assembly Top")
		(33 "B.Fab" user "Ref Des/Assembly Bottom")
	)
	(footprint ""
		(layer "F.Cu")
		(at 105.960164 -260.305296)
		(property "Reference" "C2274"
			(at 0 0 0)
			(layer "F.SilkS")
			(hide yes)
			(effects
				(font
					(size 1.27 1.27)
				)
			)
		)
		(property "Value" ""
			(at 0 0 0)
			(layer "F.Fab")
			(effects
				(font
					(size 1.27 1.27)
				)
			)
		)
		(duplicate_pad_numbers_are_jumpers no)
		(fp_line
			(start -0.7874 -0.4064)
			(end 0.7874 -0.4064)
			(stroke
				(width 0.1524)
				(type default)
			)
			(layer "F.SilkS")
		)
		(fp_line
			(start -0.7874 0.4064)
			(end -0.7874 -0.4064)
			(stroke
				(width 0.1524)
				(type default)
			)
			(layer "F.SilkS")
		)
		(fp_line
			(start 0.7874 -0.4064)
			(end 0.7874 0.4064)
			(stroke
				(width 0.1524)
				(type default)
			)
			(layer "F.SilkS")
		)
		(fp_line
			(start 0.7874 0.4064)
			(end -0.7874 0.4064)
			(stroke
				(width 0.1524)
				(type default)
			)
			(layer "F.SilkS")
		)
		(fp_line
			(start -0.67945 -0.305054)
			(end -0.12065 -0.305054)
			(stroke
				(width 0.1)
				(type default)
			)
			(layer "F.Fab")
		)
		(fp_line
			(start -0.67945 0.3048)
			(end -0.67945 -0.305054)
			(stroke
				(width 0.1)
				(type default)
			)
			(layer "F.Fab")
		)
		(fp_line
			(start -0.12065 -0.305054)
			(end -0.12065 -0.2794)
			(stroke
				(width 0.1)
				(type default)
			)
			(layer "F.Fab")
		)
		(fp_line
			(start -0.12065 -0.2794)
			(end 0.12065 -0.2794)
			(stroke
				(width 0.1)
				(type default)
			)
			(layer "F.Fab")
		)
		(fp_line
			(start -0.12065 0.2794)
			(end -0.12065 0.3048)
			(stroke
				(width 0.1)
				(type default)
			)
			(layer "F.Fab")
		)
		(fp_line
			(start -0.12065 0.3048)
			(end -0.67945 0.3048)
			(stroke
				(width 0.1)
				(type default)
			)
			(layer "F.Fab")
		)
		(fp_line
			(start 0.120396 0.2794)
			(end -0.12065 0.2794)
			(stroke
				(width 0.1)
				(type default)
			)
			(layer "F.Fab")
		)
		(fp_line
			(start 0.120396 0.3048)
			(end 0.120396 0.2794)
			(stroke
				(width 0.1)
				(type default)
			)
			(layer "F.Fab")
		)
		(fp_line
			(start 0.12065 -0.3048)
			(end 0.67945 -0.3048)
			(stroke
				(width 0.1)
				(type default)
			)
			(layer "F.Fab")
		)
		(fp_line
			(start 0.12065 -0.2794)
			(end 0.12065 -0.3048)
			(stroke
				(width 0.1)
				(type default)
			)
			(layer "F.Fab")
		)
		(fp_line
			(start 0.67945 -0.3048)
			(end 0.67945 0.3048)
			(stroke
				(width 0.1)
				(type default)
			)
			(layer "F.Fab")
		)
		(fp_line
			(start 0.67945 0.3048)
			(end 0.120396 0.3048)
			(stroke
				(width 0.1)
				(type default)
			)
			(layer "F.Fab")
		)
		(pad "1" smd circle
			(at -0.40005 0)
			(size 0 0)
			(layers "F.Cu" "F.Mask" "F.Paste")
			(net "PVDDIO_P1")
		)
		(pad "2" smd circle
			(at 0.40005 0)
			(size 0 0)
			(layers "F.Cu" "F.Mask" "F.Paste")
			(net "GND")
		)
	)
	(footprint ""
		(layer "F.Cu")
		(at 423.62374 -359.836212 180)
		(property "Reference" "R124"
			(at 0 0 180)
			(layer "F.SilkS")
			(hide yes)
			(effects
				(font
					(size 1.27 1.27)
				)
			)
		)
		(property "Value" ""
			(at 0 0 180)
			(layer "F.Fab")
			(effects
				(font
					(size 1.27 1.27)
				)
			)
		)
		(duplicate_pad_numbers_are_jumpers no)
		(fp_line
			(start 0.7874 0.4064)
			(end -0.7874 0.4064)
			(stroke
				(width 0.1524)
				(type default)
			)
			(layer "F.SilkS")
		)
		(fp_line
			(start 0.7874 -0.4064)
			(end 0.7874 0.4064)
			(stroke
				(width 0.1524)
				(type default)
			)
			(layer "F.SilkS")
		)
		(fp_line
			(start -0.7874 0.4064)
			(end -0.7874 -0.4064)
			(stroke
				(width 0.1524)
				(type default)
			)
			(layer "F.SilkS")
		)
		(fp_line
			(start -0.7874 -0.4064)
			(end 0.7874 -0.4064)
			(stroke
				(width 0.1524)
				(type default)
			)
			(layer "F.SilkS")
		)
		(fp_line
			(start 0.67945 0.3048)
			(end 0.120396 0.3048)
			(stroke
				(width 0.1)
				(type default)
			)
			(layer "F.Fab")
		)
		(fp_line
			(start 0.67945 -0.3048)
			(end 0.67945 0.3048)
			(stroke
				(width 0.1)
				(type default)
			)
			(layer "F.Fab")
		)
		(fp_line
			(start 0.12065 -0.2794)
			(end 0.12065 -0.3048)
			(stroke
				(width 0.1)
				(type default)
			)
			(layer "F.Fab")
		)
		(fp_line
			(start 0.12065 -0.3048)
			(end 0.67945 -0.3048)
			(stroke
				(width 0.1)
				(type default)
			)
			(layer "F.Fab")
		)
		(fp_line
			(start 0.120396 0.3048)
			(end 0.120396 0.2794)
			(stroke
				(width 0.1)
				(type default)
			)
			(layer "F.Fab")
		)
		(fp_line
			(start 0.120396 0.2794)
			(end -0.12065 0.2794)
			(stroke
				(width 0.1)
				(type default)
			)
			(layer "F.Fab")
		)
		(fp_line
			(start -0.12065 0.3048)
			(end -0.67945 0.3048)
			(stroke
				(width 0.1)
				(type default)
			)
			(layer "F.Fab")
		)
		(fp_line
			(start -0.12065 0.2794)
			(end -0.12065 0.3048)
			(stroke
				(width 0.1)
				(type default)
			)
			(layer "F.Fab")
		)
		(fp_line
			(start -0.12065 -0.2794)
			(end 0.12065 -0.2794)
			(stroke
				(width 0.1)
				(type default)
			)
			(layer "F.Fab")
		)
		(fp_line
			(start -0.12065 -0.305054)
			(end -0.12065 -0.2794)
			(stroke
				(width 0.1)
				(type default)
			)
			(layer "F.Fab")
		)
		(fp_line
			(start -0.67945 0.3048)
			(end -0.67945 -0.305054)
			(stroke
				(width 0.1)
				(type default)
			)
			(layer "F.Fab")
		)
		(fp_line
			(start -0.67945 -0.305054)
			(end -0.12065 -0.305054)
			(stroke
				(width 0.1)
				(type default)
			)
			(layer "F.Fab")
		)
		(pad "1" smd circle
			(at -0.40005 0 180)
			(size 0 0)
			(layers "F.Cu" "F.Mask" "F.Paste")
			(net "PVDD18_S5_P0")
		)
		(pad "2" smd circle
			(at 0.40005 0 180)
			(size 0 0)
			(layers "F.Cu" "F.Mask" "F.Paste")
			(net "PVDD11_S3_P0_OCP_N_R")
		)
	)
	(footprint ""
		(layer "F.Cu")
		(at 166.548308 -352.278442 90)
		(property "Reference" "PC95"
			(at 0 0 90)
			(layer "F.SilkS")
			(hide yes)
			(effects
				(font
					(size 1.27 1.27)
				)
			)
		)
		(property "Value" ""
			(at 0 0 90)
			(layer "F.Fab")
			(effects
				(font
					(size 1.27 1.27)
				)
			)
		)
		(duplicate_pad_numbers_are_jumpers no)
		(fp_line
			(start 0.7874 -0.4064)
			(end 0.7874 0.4064)
			(stroke
				(width 0.1524)
				(type default)
			)
			(layer "F.SilkS")
		)
		(fp_line
			(start -0.7874 -0.4064)
			(end 0.7874 -0.4064)
			(stroke
				(width 0.1524)
				(type default)
			)
			(layer "F.SilkS")
		)
		(fp_line
			(start 0.7874 0.4064)
			(end -0.7874 0.4064)
			(stroke
				(width 0.1524)
				(type default)
			)
			(layer "F.SilkS")
		)
		(fp_line
			(start -0.7874 0.4064)
			(end -0.7874 -0.4064)
			(stroke
				(width 0.1524)
				(type default)
			)
			(layer "F.SilkS")
		)
		(fp_line
			(start -0.12065 -0.305054)
			(end -0.12065 -0.2794)
			(stroke
				(width 0.1)
				(type default)
			)
			(layer "F.Fab")
		)
		(fp_line
			(start -0.67945 -0.305054)
			(end -0.12065 -0.305054)
			(stroke
				(width 0.1)
				(type default)
			)
			(layer "F.Fab")
		)
		(fp_line
			(start 0.67945 -0.3048)
			(end 0.67945 0.3048)
			(stroke
				(width 0.1)
				(type default)
			)
			(layer "F.Fab")
		)
		(fp_line
			(start 0.12065 -0.3048)
			(end 0.67945 -0.3048)
			(stroke
				(width 0.1)
				(type default)
			)
			(layer "F.Fab")
		)
		(fp_line
			(start 0.12065 -0.2794)
			(end 0.12065 -0.3048)
			(stroke
				(width 0.1)
				(type default)
			)
			(layer "F.Fab")
		)
		(fp_line
			(start -0.12065 -0.2794)
			(end 0.12065 -0.2794)
			(stroke
				(width 0.1)
				(type default)
			)
			(layer "F.Fab")
		)
		(fp_line
			(start 0.120396 0.2794)
			(end -0.12065 0.2794)
			(stroke
				(width 0.1)
				(type default)
			)
			(layer "F.Fab")
		)
		(fp_line
			(start -0.12065 0.2794)
			(end -0.12065 0.3048)
			(stroke
				(width 0.1)
				(type default)
			)
			(layer "F.Fab")
		)
		(fp_line
			(start 0.67945 0.3048)
			(end 0.120396 0.3048)
			(stroke
				(width 0.1)
				(type default)
			)
			(layer "F.Fab")
		)
		(fp_line
			(start 0.120396 0.3048)
			(end 0.120396 0.2794)
			(stroke
				(width 0.1)
				(type default)
			)
			(layer "F.Fab")
		)
		(fp_line
			(start -0.12065 0.3048)
			(end -0.67945 0.3048)
			(stroke
				(width 0.1)
				(type default)
			)
			(layer "F.Fab")
		)
		(fp_line
			(start -0.67945 0.3048)
			(end -0.67945 -0.305054)
			(stroke
				(width 0.1)
				(type default)
			)
			(layer "F.Fab")
		)
		(pad "1" smd circle
			(at -0.40005 0 90)
			(size 0 0)
			(layers "F.Cu" "F.Mask" "F.Paste")
			(net "PVDD11_S3_P1_VCC")
		)
		(pad "2" smd circle
			(at 0.40005 0 90)
			(size 0 0)
			(layers "F.Cu" "F.Mask" "F.Paste")
			(net "GND")
		)
	)
	(footprint ""
		(layer "F.Cu")
		(at 330.371958 -193.163952 -90)
		(property "Reference" "R416"
			(at 0 0 270)
			(layer "F.SilkS")
			(hide yes)
			(effects
				(font
					(size 1.27 1.27)
				)
			)
		)
		(property "Value" ""
			(at 0 0 270)
			(layer "F.Fab")
			(effects
				(font
					(size 1.27 1.27)
				)
			)
		)
		(duplicate_pad_numbers_are_jumpers no)
		(fp_line
			(start -0.7874 0.4064)
			(end -0.7874 -0.4064)
			(stroke
				(width 0.1524)
				(type default)
			)
			(layer "F.SilkS")
		)
		(fp_line
			(start 0.7874 0.4064)
			(end -0.7874 0.4064)
			(stroke
				(width 0.1524)
				(type default)
			)
			(layer "F.SilkS")
		)
		(fp_line
			(start -0.7874 -0.4064)
			(end 0.7874 -0.4064)
			(stroke
				(width 0.1524)
				(type default)
			)
			(layer "F.SilkS")
		)
		(fp_line
			(start 0.7874 -0.4064)
			(end 0.7874 0.4064)
			(stroke
				(width 0.1524)
				(type default)
			)
			(layer "F.SilkS")
		)
		(fp_line
			(start -0.67945 0.3048)
			(end -0.67945 -0.305054)
			(stroke
				(width 0.1)
				(type default)
			)
			(layer "F.Fab")
		)
		(fp_line
			(start -0.12065 0.3048)
			(end -0.67945 0.3048)
			(stroke
				(width 0.1)
				(type default)
			)
			(layer "F.Fab")
		)
		(fp_line
			(start 0.120396 0.3048)
			(end 0.120396 0.2794)
			(stroke
				(width 0.1)
				(type default)
			)
			(layer "F.Fab")
		)
		(fp_line
			(start 0.67945 0.3048)
			(end 0.120396 0.3048)
			(stroke
				(width 0.1)
				(type default)
			)
			(layer "F.Fab")
		)
		(fp_line
			(start -0.12065 0.2794)
			(end -0.12065 0.3048)
			(stroke
				(width 0.1)
				(type default)
			)
			(layer "F.Fab")
		)
		(fp_line
			(start 0.120396 0.2794)
			(end -0.12065 0.2794)
			(stroke
				(width 0.1)
				(type default)
			)
			(layer "F.Fab")
		)
		(fp_line
			(start -0.12065 -0.2794)
			(end 0.12065 -0.2794)
			(stroke
				(width 0.1)
				(type default)
			)
			(layer "F.Fab")
		)
		(fp_line
			(start 0.12065 -0.2794)
			(end 0.12065 -0.3048)
			(stroke
				(width 0.1)
				(type default)
			)
			(layer "F.Fab")
		)
		(fp_line
			(start 0.12065 -0.3048)
			(end 0.67945 -0.3048)
			(stroke
				(width 0.1)
				(type default)
			)
			(layer "F.Fab")
		)
		(fp_line
			(start 0.67945 -0.3048)
			(end 0.67945 0.3048)
			(stroke
				(width 0.1)
				(type default)
			)
			(layer "F.Fab")
		)
		(fp_line
			(start -0.67945 -0.305054)
			(end -0.12065 -0.305054)
			(stroke
				(width 0.1)
				(type default)
			)
			(layer "F.Fab")
		)
		(fp_line
			(start -0.12065 -0.305054)
			(end -0.12065 -0.2794)
			(stroke
				(width 0.1)
				(type default)
			)
			(layer "F.Fab")
		)
		(pad "1" smd circle
			(at -0.40005 0 270)
			(size 0 0)
			(layers "F.Cu" "F.Mask" "F.Paste")
			(net "CPU0_XTRIG_L7")
		)
		(pad "2" smd circle
			(at 0.40005 0 270)
			(size 0 0)
			(layers "F.Cu" "F.Mask" "F.Paste")
			(net "PVDD18_S5_P0")
		)
	)
	(footprint ""
		(layer "F.Cu")
		(at 52.143406 -152.20823 180)
		(property "Reference" "PC83"
			(at 0 0 180)
			(layer "F.SilkS")
			(hide yes)
			(effects
				(font
					(size 1.27 1.27)
				)
			)
		)
		(property "Value" ""
			(at 0 0 180)
			(layer "F.Fab")
			(effects
				(font
					(size 1.27 1.27)
				)
			)
		)
		(duplicate_pad_numbers_are_jumpers no)
		(fp_line
			(start 1.524 0.762)
			(end -1.524 0.762)
			(stroke
				(width 0.1524)
				(type default)
			)
			(layer "F.SilkS")
		)
		(fp_line
			(start 1.524 -0.762)
			(end 1.524 0.762)
			(stroke
				(width 0.1524)
				(type default)
			)
			(layer "F.SilkS")
		)
		(fp_line
			(start -1.524 0.762)
			(end -1.524 -0.762)
			(stroke
				(width 0.1524)
				(type default)
			)
			(layer "F.SilkS")
		)
		(fp_line
			(start -1.524 -0.762)
			(end 1.524 -0.762)
			(stroke
				(width 0.1524)
				(type default)
			)
			(layer "F.SilkS")
		)
		(fp_line
			(start 1.1049 0.724916)
			(end 1.1049 -0.724916)
			(stroke
				(width 0.1)
				(type default)
			)
			(layer "F.Fab")
		)
		(fp_line
			(start 1.1049 -0.724916)
			(end -1.1049 -0.724916)
			(stroke
				(width 0.1)
				(type default)
			)
			(layer "F.Fab")
		)
		(fp_line
			(start -1.1049 0.724916)
			(end 1.1049 0.724916)
			(stroke
				(width 0.1)
				(type default)
			)
			(layer "F.Fab")
		)
		(fp_line
			(start -1.1049 -0.724916)
			(end -1.1049 0.724916)
			(stroke
				(width 0.1)
				(type default)
			)
			(layer "F.Fab")
		)
		(pad "1" smd rect
			(at -0.889 0)
			(size 1.016 1.27)
			(layers "F.Cu" "F.Mask" "F.Paste")
			(net "PVDD18_S5_P1")
		)
		(pad "2" smd rect
			(at 0.889 0)
			(size 1.016 1.27)
			(layers "F.Cu" "F.Mask" "F.Paste")
			(net "GND")
		)
	)
	(footprint ""
		(layer "F.Cu")
		(at 28.274772 -432.477164)
		(property "Reference" "U194"
			(at -4.766818 -2.04216 0)
			(unlocked yes)
			(layer "F.SilkS")
			(effects
				(font
					(size 0.7874 0.5842)
					(thickness 0.1524)
				)
				(justify left)
			)
		)
		(property "Value" ""
			(at 0 0 0)
			(layer "F.Fab")
			(effects
				(font
					(size 1.27 1.27)
				)
			)
		)
		(duplicate_pad_numbers_are_jumpers no)
		(fp_line
			(start -1.3716 -1.524)
			(end -0.508 -1.524)
			(stroke
				(width 0.1524)
				(type default)
			)
			(layer "F.SilkS")
		)
		(fp_line
			(start -1.3716 1.524)
			(end -1.3716 -1.524)
			(stroke
				(width 0.1524)
				(type default)
			)
			(layer "F.SilkS")
		)
		(fp_line
			(start -0.508 -1.524)
			(end 0 -1.016)
			(stroke
				(width 0.1524)
				(type default)
			)
			(layer "F.SilkS")
		)
		(fp_line
			(start 0 -1.016)
			(end 0.508 -1.524)
			(stroke
				(width 0.1524)
				(type default)
			)
			(layer "F.SilkS")
		)
		(fp_line
			(start 0.508 -1.524)
			(end 1.3716 -1.524)
			(stroke
				(width 0.1524)
				(type default)
			)
			(layer "F.SilkS")
		)
		(fp_line
			(start 1.3716 -1.524)
			(end 1.3716 1.524)
			(stroke
				(width 0.1524)
				(type default)
			)
			(layer "F.SilkS")
		)
		(fp_line
			(start 1.3716 1.524)
			(end -1.3716 1.524)
			(stroke
				(width 0.1524)
				(type default)
			)
			(layer "F.SilkS")
		)
		(fp_poly
			(pts
				(xy -3.651758 -1.010666) (xy -3.47345 -1.609598) (xy -3.03657 -1.137158)
			)
			(stroke
				(width 0)
				(type default)
			)
			(fill yes)
			(layer "F.SilkS")
		)
		(fp_line
			(start -2.54 -1.0668)
			(end -1.5494 -1.0668)
			(stroke
				(width 0.1)
				(type default)
			)
			(layer "F.Fab")
		)
		(fp_line
			(start -2.54 1.0668)
			(end -2.54 -1.0668)
			(stroke
				(width 0.1)
				(type default)
			)
			(layer "F.Fab")
		)
		(fp_line
			(start -1.5494 -1.524)
			(end 1.5494 -1.524)
			(stroke
				(width 0.1)
				(type default)
			)
			(layer "F.Fab")
		)
		(fp_line
			(start -1.5494 -1.0668)
			(end -1.5494 -1.524)
			(stroke
				(width 0.1)
				(type default)
			)
			(layer "F.Fab")
		)
		(fp_line
			(start -1.5494 1.0668)
			(end -2.54 1.0668)
			(stroke
				(width 0.1)
				(type default)
			)
			(layer "F.Fab")
		)
		(fp_line
			(start -1.5494 1.0668)
			(end -1.5494 -1.0668)
			(stroke
				(width 0.1)
				(type default)
			)
			(layer "F.Fab")
		)
		(fp_line
			(start -1.5494 1.524)
			(end -1.5494 1.0668)
			(stroke
				(width 0.1)
				(type default)
			)
			(layer "F.Fab")
		)
		(fp_line
			(start 1.5494 -1.524)
			(end 1.5494 -1.0668)
			(stroke
				(width 0.1)
				(type default)
			)
			(layer "F.Fab")
		)
		(fp_line
			(start 1.5494 -1.0668)
			(end 1.5494 1.0668)
			(stroke
				(width 0.1)
				(type default)
			)
			(layer "F.Fab")
		)
		(fp_line
			(start 1.5494 -1.0668)
			(end 2.54 -1.0668)
			(stroke
				(width 0.1)
				(type default)
			)
			(layer "F.Fab")
		)
		(fp_line
			(start 1.5494 1.0668)
			(end 1.5494 1.524)
			(stroke
				(width 0.1)
				(type default)
			)
			(layer "F.Fab")
		)
		(fp_line
			(start 1.5494 1.524)
			(end -1.5494 1.524)
			(stroke
				(width 0.1)
				(type default)
			)
			(layer "F.Fab")
		)
		(fp_line
			(start 2.54 -1.0668)
			(end 2.54 1.0668)
			(stroke
				(width 0.1)
				(type default)
			)
			(layer "F.Fab")
		)
		(fp_line
			(start 2.54 1.0668)
			(end 1.5494 1.0668)
			(stroke
				(width 0.1)
				(type default)
			)
			(layer "F.Fab")
		)
		(fp_poly
			(pts
				(xy -3.60172 -0.719328) (xy -3.60172 -1.344168) (xy -3.048 -1.016)
			)
			(stroke
				(width 0)
				(type default)
			)
			(fill yes)
			(layer "F.Fab")
		)
		(pad "1" smd rect
			(at -2.232406 -0.975106 270)
			(size 0.3556 1.4224)
			(layers "F.Cu" "F.Mask" "F.Paste")
			(net "SMB_BMC_GPU_EN_R1")
		)
		(pad "2" smd rect
			(at -2.232406 -0.32512 270)
			(size 0.3556 1.4224)
			(layers "F.Cu" "F.Mask" "F.Paste")
			(net "SMB_1_BMC_GPU_BUF_R_SCL")
		)
		(pad "3" smd rect
			(at -2.232406 0.32512 270)
			(size 0.3556 1.4224)
			(layers "F.Cu" "F.Mask" "F.Paste")
			(net "SMB_1_BMC_GPU_R_SCL")
		)
		(pad "4" smd rect
			(at -2.232406 0.975106 270)
			(size 0.3556 1.4224)
			(layers "F.Cu" "F.Mask" "F.Paste")
			(net "GND")
		)
		(pad "5" smd rect
			(at 2.232406 0.975106 270)
			(size 0.3556 1.4224)
			(layers "F.Cu" "F.Mask" "F.Paste")
			(net "Net_10760")
		)
		(pad "6" smd rect
			(at 2.232406 0.32512 270)
			(size 0.3556 1.4224)
			(layers "F.Cu" "F.Mask" "F.Paste")
			(net "SMB_1_BMC_GPU_R_SDA")
		)
		(pad "7" smd rect
			(at 2.232406 -0.32512 270)
			(size 0.3556 1.4224)
			(layers "F.Cu" "F.Mask" "F.Paste")
			(net "SMB_1_BMC_GPU_BUF_R_SDA")
		)
		(pad "8" smd rect
			(at 2.232406 -0.975106 270)
			(size 0.3556 1.4224)
			(layers "F.Cu" "F.Mask" "F.Paste")
			(net "P3V3_AUX")
		)
	)
)
